(kicad_pcb
	(version 20241229)
	(generator "pcbnew")
	(generator_version "9.0")
	(general
		(thickness 1.294)
		(legacy_teardrops no)
	)
	(paper "A3")
	(title_block
		(title "Kintex 410T devboard")
		(date "2024-04-03")
		(rev "1.1.2")
		(comment 9 "footprint 170 of 975 (U1), pads 240-296 of 900")
	)
	(layers
		(0 "F.Cu" mixed)
		(4 "In1.Cu" power)
		(6 "In2.Cu" power)
		(8 "In3.Cu" mixed)
		(10 "In4.Cu" power)
		(12 "In5.Cu" mixed)
		(14 "In6.Cu" power)
		(16 "In7.Cu" mixed)
		(18 "In8.Cu" power)
		(2 "B.Cu" mixed)
		(9 "F.Adhes" user "F.Adhesive")
		(11 "B.Adhes" user "B.Adhesive")
		(13 "F.Paste" user)
		(15 "B.Paste" user)
		(5 "F.SilkS" user "F.Silkscreen")
		(7 "B.SilkS" user "B.Silkscreen")
		(1 "F.Mask" user)
		(3 "B.Mask" user)
		(17 "Dwgs.User" user "User.Drawings")
		(19 "Cmts.User" user "User.Comments")
		(21 "Eco1.User" user "User.Eco1")
		(23 "Eco2.User" user "User.Eco2")
		(25 "Edge.Cuts" user)
		(27 "Margin" user)
		(31 "F.CrtYd" user "F.Courtyard")
		(29 "B.CrtYd" user "B.Courtyard")
		(35 "F.Fab" user)
		(33 "B.Fab" user)
	)
	(footprint "antmicro-footprints:BGA-900_31x31mm_Layout30x30_P1x1mm_FFG900"
		(locked yes)
		(layer "F.Cu")
		(at 200 130)
		(property "Reference" "U1"
			(at -15.74 -15.78 0)
			(layer "F.SilkS")
			(effects
				(font
					(size 0.7 0.7)
					(thickness 0.15)
				)
				(justify left bottom)
			)
		)
		(property "Value" "XC7K410T-2FFG900I"
			(at -4.436 17.635 0)
			(layer "F.Fab")
			(effects
				(font
					(size 0.7 0.7)
					(thickness 0.15)
				)
				(justify left bottom)
			)
		)
		(property "Description" "FPGA, Kintex-7, MMCM, PLL, 350 I/O's, 710 MHz, 406720 Cells, 970 mV to 1.03 V, FCBGA-900"
			(at 0 0 0)
			(layer "F.Fab")
			(hide yes)
			(effects
				(font
					(size 1.27 1.27)
					(thickness 0.15)
				)
			)
		)
		(property "Author" "Antmicro"
			(at 0 0 0)
			(layer "F.Fab")
			(hide yes)
			(effects
				(font
					(size 1 1)
					(thickness 0.15)
				)
			)
		)
		(property "License" "Apache-2.0"
			(at 0 0 0)
			(layer "F.Fab")
			(hide yes)
			(effects
				(font
					(size 1 1)
					(thickness 0.15)
				)
			)
		)
		(property "MPN" "XC7K410T-2FFG900I"
			(at 0 0 0)
			(layer "F.Fab")
			(hide yes)
			(effects
				(font
					(size 1 1)
					(thickness 0.15)
				)
			)
		)
		(property "Manufacturer" "AMD-Xilinx"
			(at 0 0 0)
			(layer "F.Fab")
			(hide yes)
			(effects
				(font
					(size 1 1)
					(thickness 0.15)
				)
			)
		)
		(sheetname "FPGA supply")
		(sheetfile "fpga-supply.kicad_sch")
		(attr smd)
		(pad "AG30" smd circle
			(at 14.5 11.5)
			(size 0.5 0.5)
			(property pad_prop_bga)
			(layers "F.Cu" "F.Mask" "F.Paste")
			(net 633 "unconnected-(U1A-IO_L18P_T2_13-PadAG30)")
			(pinfunction "IO_L18P_T2_13")
			(pintype "bidirectional+no_connect")
			(die_length 20.457)
			(solder_mask_margin 0.02)
		)
		(pad "AH1" smd circle
			(at -14.5 12.5)
			(size 0.5 0.5)
			(property pad_prop_bga)
			(layers "F.Cu" "F.Mask" "F.Paste")
			(net 561 "/DRAM + SRAM/DDR.~{CS}")
			(pinfunction "IO_L15N_T2_DQS_34")
			(pintype "bidirectional")
			(die_length 22.335)
			(solder_mask_margin 0.02)
		)
		(pad "AH2" smd circle
			(at -13.5 12.5)
			(size 0.5 0.5)
			(property pad_prop_bga)
			(layers "F.Cu" "F.Mask" "F.Paste")
			(net 550 "/DRAM + SRAM/DDR.CKE")
			(pinfunction "IO_L16P_T2_34")
			(pintype "bidirectional")
			(die_length 23.594)
			(solder_mask_margin 0.02)
		)
		(pad "AH3" smd circle
			(at -12.5 12.5)
			(size 0.5 0.5)
			(property pad_prop_bga)
			(layers "F.Cu" "F.Mask" "F.Paste")
			(net 1 "GND")
			(pinfunction "GND")
			(pintype "passive")
			(solder_mask_margin 0.02)
		)
		(pad "AH4" smd circle
			(at -11.5 12.5)
			(size 0.5 0.5)
			(property pad_prop_bga)
			(layers "F.Cu" "F.Mask" "F.Paste")
			(net 554 "/DRAM + SRAM/DDR.~{RESET}")
			(pinfunction "IO_L13P_T2_MRCC_34")
			(pintype "bidirectional")
			(die_length 21.051)
			(solder_mask_margin 0.02)
		)
		(pad "AH5" smd circle
			(at -10.5 12.5)
			(size 0.5 0.5)
			(property pad_prop_bga)
			(layers "F.Cu" "F.Mask" "F.Paste")
			(net 635 "unconnected-(U1E-IO_L14N_T2_SRCC_34-PadAH5)")
			(pinfunction "IO_L14N_T2_SRCC_34")
			(pintype "bidirectional+no_connect")
			(die_length 23.368)
			(solder_mask_margin 0.02)
		)
		(pad "AH6" smd circle
			(at -9.5 12.5)
			(size 0.5 0.5)
			(property pad_prop_bga)
			(layers "F.Cu" "F.Mask" "F.Paste")
			(net 636 "unconnected-(U1E-IO_L14P_T2_SRCC_34-PadAH6)")
			(pinfunction "IO_L14P_T2_SRCC_34")
			(pintype "bidirectional+no_connect")
			(die_length 23.691)
			(solder_mask_margin 0.02)
		)
		(pad "AH7" smd circle
			(at -8.5 12.5)
			(size 0.5 0.5)
			(property pad_prop_bga)
			(layers "F.Cu" "F.Mask" "F.Paste")
			(net 656 "/DRAM + SRAM/DDR.DQS_P")
			(pinfunction "IO_L21P_T3_DQS_34")
			(pintype "bidirectional")
			(die_length 20.353)
			(solder_mask_margin 0.02)
		)
		(pad "AH8" smd circle
			(at -7.5 12.5)
			(size 0.5 0.5)
			(property pad_prop_bga)
			(layers "F.Cu" "F.Mask" "F.Paste")
			(net 25 "+1V35")
			(pinfunction "VCCO_34")
			(pintype "passive")
			(solder_mask_margin 0.02)
		)
		(pad "AH9" smd circle
			(at -6.5 12.5)
			(size 0.5 0.5)
			(property pad_prop_bga)
			(layers "F.Cu" "F.Mask" "F.Paste")
			(net 465 "unconnected-(U1E-IO_L16N_T2_33-PadAH9)")
			(pinfunction "IO_L16N_T2_33")
			(pintype "bidirectional+no_connect")
			(die_length 15.598)
			(solder_mask_margin 0.02)
		)
		(pad "AH10" smd circle
			(at -5.5 12.5)
			(size 0.5 0.5)
			(property pad_prop_bga)
			(layers "F.Cu" "F.Mask" "F.Paste")
			(net 466 "unconnected-(U1E-IO_L13N_T2_MRCC_33-PadAH10)")
			(pinfunction "IO_L13N_T2_MRCC_33")
			(pintype "bidirectional+no_connect")
			(die_length 19.153)
			(solder_mask_margin 0.02)
		)
		(pad "AH11" smd circle
			(at -4.5 12.5)
			(size 0.5 0.5)
			(property pad_prop_bga)
			(layers "F.Cu" "F.Mask" "F.Paste")
			(net 467 "unconnected-(U1E-IO_L18P_T2_33-PadAH11)")
			(pinfunction "IO_L18P_T2_33")
			(pintype "bidirectional+no_connect")
			(die_length 17.477)
			(solder_mask_margin 0.02)
		)
		(pad "AH12" smd circle
			(at -3.5 12.5)
			(size 0.5 0.5)
			(property pad_prop_bga)
			(layers "F.Cu" "F.Mask" "F.Paste")
			(net 404 "/FPGA Bank 33 & 34/USR_FLASH_0.DQ2")
			(pinfunction "IO_L24N_T3_33")
			(pintype "bidirectional")
			(die_length 19.902)
			(solder_mask_margin 0.02)
		)
		(pad "AH13" smd circle
			(at -2.5 12.5)
			(size 0.5 0.5)
			(property pad_prop_bga)
			(layers "F.Cu" "F.Mask" "F.Paste")
			(net 1 "GND")
			(pinfunction "GND")
			(pintype "passive")
			(solder_mask_margin 0.02)
		)
		(pad "AH14" smd circle
			(at -1.5 12.5)
			(size 0.5 0.5)
			(property pad_prop_bga)
			(layers "F.Cu" "F.Mask" "F.Paste")
			(net 469 "unconnected-(U1E-IO_L21P_T3_DQS_33-PadAH14)")
			(pinfunction "IO_L21P_T3_DQS_33")
			(pintype "bidirectional+no_connect")
			(die_length 23.831)
			(solder_mask_margin 0.02)
		)
		(pad "AH15" smd circle
			(at -0.5 12.5)
			(size 0.5 0.5)
			(property pad_prop_bga)
			(layers "F.Cu" "F.Mask" "F.Paste")
			(net 500 "/FPGA Bank 12 & 13/USB_USER.SUS")
			(pinfunction "IO_L2N_T0_32")
			(pintype "bidirectional")
			(die_length 20.849)
			(solder_mask_margin 0.02)
		)
		(pad "AH16" smd circle
			(at 0.5 12.5)
			(size 0.5 0.5)
			(property pad_prop_bga)
			(layers "F.Cu" "F.Mask" "F.Paste")
			(net 638 "unconnected-(U1D-IO_L3P_T0_DQS_32-PadAH16)")
			(pinfunction "IO_L3P_T0_DQS_32")
			(pintype "bidirectional+no_connect")
			(die_length 20.668)
			(solder_mask_margin 0.02)
		)
		(pad "AH17" smd circle
			(at 1.5 12.5)
			(size 0.5 0.5)
			(property pad_prop_bga)
			(layers "F.Cu" "F.Mask" "F.Paste")
			(net 639 "/FPGA Bank 12 & 13/USB_USER.VPO")
			(pinfunction "IO_L5P_T0_32")
			(pintype "bidirectional")
			(die_length 20.893)
			(solder_mask_margin 0.02)
		)
		(pad "AH18" smd circle
			(at 2.5 12.5)
			(size 0.5 0.5)
			(property pad_prop_bga)
			(layers "F.Cu" "F.Mask" "F.Paste")
			(net 26 "+1V8")
			(pinfunction "VCCO_32")
			(pintype "passive")
			(solder_mask_margin 0.02)
		)
		(pad "AH19" smd circle
			(at 3.5 12.5)
			(size 0.5 0.5)
			(property pad_prop_bga)
			(layers "F.Cu" "F.Mask" "F.Paste")
			(net 644 "unconnected-(U1D-IO_L8N_T1_32-PadAH19)")
			(pinfunction "IO_L8N_T1_32")
			(pintype "bidirectional+no_connect")
			(die_length 24.8)
			(solder_mask_margin 0.02)
		)
		(pad "AH20" smd circle
			(at 4.5 12.5)
			(size 0.5 0.5)
			(property pad_prop_bga)
			(layers "F.Cu" "F.Mask" "F.Paste")
			(net 492 "/FPGA Bank 12 & 13/CW_HEADER.IO3")
			(pinfunction "IO_L22N_T3_12")
			(pintype "bidirectional")
			(die_length 10.515)
			(solder_mask_margin 0.02)
		)
		(pad "AH21" smd circle
			(at 5.5 12.5)
			(size 0.5 0.5)
			(property pad_prop_bga)
			(layers "F.Cu" "F.Mask" "F.Paste")
			(net 1358 "/SUP_MCU.A2")
			(pinfunction "IO_L23P_T3_12")
			(pintype "bidirectional")
			(die_length 12.587)
			(solder_mask_margin 0.02)
		)
		(pad "AH22" smd circle
			(at 6.5 12.5)
			(size 0.5 0.5)
			(property pad_prop_bga)
			(layers "F.Cu" "F.Mask" "F.Paste")
			(net 491 "/FPGA Bank 12 & 13/CW_HEADER.IO2")
			(pinfunction "IO_L20N_T3_12")
			(pintype "bidirectional")
			(die_length 9.887)
			(solder_mask_margin 0.02)
		)
		(pad "AH23" smd circle
			(at 7.5 12.5)
			(size 0.5 0.5)
			(property pad_prop_bga)
			(layers "F.Cu" "F.Mask" "F.Paste")
			(net 1 "GND")
			(pinfunction "GND")
			(pintype "passive")
			(solder_mask_margin 0.02)
		)
		(pad "AH24" smd circle
			(at 8.5 12.5)
			(size 0.5 0.5)
			(property pad_prop_bga)
			(layers "F.Cu" "F.Mask" "F.Paste")
			(net 1359 "/SUP_MCU.A5")
			(pinfunction "IO_L14N_T2_SRCC_12")
			(pintype "bidirectional")
			(die_length 11.774)
			(solder_mask_margin 0.02)
		)
		(pad "AH25" smd circle
			(at 9.5 12.5)
			(size 0.5 0.5)
			(property pad_prop_bga)
			(layers "F.Cu" "F.Mask" "F.Paste")
			(net 1379 "/SUP_MCU.D2")
			(pinfunction "IO_L18N_T2_12")
			(pintype "bidirectional")
			(die_length 13.379)
			(solder_mask_margin 0.02)
		)
		(pad "AH26" smd circle
			(at 10.5 12.5)
			(size 0.5 0.5)
			(property pad_prop_bga)
			(layers "F.Cu" "F.Mask" "F.Paste")
			(net 645 "unconnected-(U1A-IO_L22P_T3_13-PadAH26)")
			(pinfunction "IO_L22P_T3_13")
			(pintype "bidirectional+no_connect")
			(die_length 18.804)
			(solder_mask_margin 0.02)
		)
		(pad "AH27" smd circle
			(at 11.5 12.5)
			(size 0.5 0.5)
			(property pad_prop_bga)
			(layers "F.Cu" "F.Mask" "F.Paste")
			(net 1300 "/USER_IO.LED_GREEN1")
			(pinfunction "IO_L22N_T3_13")
			(pintype "bidirectional")
			(die_length 17.115)
			(solder_mask_margin 0.02)
		)
		(pad "AH28" smd circle
			(at 12.5 12.5)
			(size 0.5 0.5)
			(property pad_prop_bga)
			(layers "F.Cu" "F.Mask" "F.Paste")
			(net 24 "+3V3")
			(pinfunction "VCCO_13")
			(pintype "passive")
			(solder_mask_margin 0.02)
		)
		(pad "AH29" smd circle
			(at 13.5 12.5)
			(size 0.5 0.5)
			(property pad_prop_bga)
			(layers "F.Cu" "F.Mask" "F.Paste")
			(net 646 "unconnected-(U1A-IO_L13N_T2_MRCC_13-PadAH29)")
			(pinfunction "IO_L13N_T2_MRCC_13")
			(pintype "bidirectional+no_connect")
			(die_length 19.428)
			(solder_mask_margin 0.02)
		)
		(pad "AH30" smd circle
			(at 14.5 12.5)
			(size 0.5 0.5)
			(property pad_prop_bga)
			(layers "F.Cu" "F.Mask" "F.Paste")
			(net 647 "unconnected-(U1A-IO_L18N_T2_13-PadAH30)")
			(pinfunction "IO_L18N_T2_13")
			(pintype "bidirectional+no_connect")
			(die_length 20.408)
			(solder_mask_margin 0.02)
		)
		(pad "AJ1" smd circle
			(at -14.5 13.5)
			(size 0.5 0.5)
			(property pad_prop_bga)
			(layers "F.Cu" "F.Mask" "F.Paste")
			(net 648 "unconnected-(U1E-IO_L17P_T2_34-PadAJ1)")
			(pinfunction "IO_L17P_T2_34")
			(pintype "bidirectional+no_connect")
			(die_length 25.396)
			(solder_mask_margin 0.02)
		)
		(pad "AJ2" smd circle
			(at -13.5 13.5)
			(size 0.5 0.5)
			(property pad_prop_bga)
			(layers "F.Cu" "F.Mask" "F.Paste")
			(net 553 "/DRAM + SRAM/DDR.ODT")
			(pinfunction "IO_L16N_T2_34")
			(pintype "bidirectional")
			(die_length 23.465)
			(solder_mask_margin 0.02)
		)
		(pad "AJ3" smd circle
			(at -12.5 13.5)
			(size 0.5 0.5)
			(property pad_prop_bga)
			(layers "F.Cu" "F.Mask" "F.Paste")
			(net 651 "unconnected-(U1E-IO_L18P_T2_34-PadAJ3)")
			(pinfunction "IO_L18P_T2_34")
			(pintype "bidirectional+no_connect")
			(die_length 23.099)
			(solder_mask_margin 0.02)
		)
		(pad "AJ4" smd circle
			(at -11.5 13.5)
			(size 0.5 0.5)
			(property pad_prop_bga)
			(layers "F.Cu" "F.Mask" "F.Paste")
			(net 652 "unconnected-(U1E-IO_L13N_T2_MRCC_34-PadAJ4)")
			(pinfunction "IO_L13N_T2_MRCC_34")
			(pintype "bidirectional+no_connect")
			(die_length 21.012)
			(solder_mask_margin 0.02)
		)
		(pad "AJ5" smd circle
			(at -10.5 13.5)
			(size 0.5 0.5)
			(property pad_prop_bga)
			(layers "F.Cu" "F.Mask" "F.Paste")
			(net 25 "+1V35")
			(pinfunction "VCCO_34")
			(pintype "passive")
			(solder_mask_margin 0.02)
		)
		(pad "AJ6" smd circle
			(at -9.5 13.5)
			(size 0.5 0.5)
			(property pad_prop_bga)
			(layers "F.Cu" "F.Mask" "F.Paste")
			(net 657 "/DRAM + SRAM/DDR.DQ3")
			(pinfunction "IO_L22P_T3_34")
			(pintype "bidirectional")
			(die_length 20.732)
			(solder_mask_margin 0.02)
		)
		(pad "AJ7" smd circle
			(at -8.5 13.5)
			(size 0.5 0.5)
			(property pad_prop_bga)
			(layers "F.Cu" "F.Mask" "F.Paste")
			(net 658 "/DRAM + SRAM/DDR.DQS_N")
			(pinfunction "IO_L21N_T3_DQS_34")
			(pintype "bidirectional")
			(die_length 20.068)
			(solder_mask_margin 0.02)
		)
		(pad "AJ8" smd circle
			(at -7.5 13.5)
			(size 0.5 0.5)
			(property pad_prop_bga)
			(layers "F.Cu" "F.Mask" "F.Paste")
			(net 659 "/DRAM + SRAM/DDR.DQ5")
			(pinfunction "IO_L23P_T3_34")
			(pintype "bidirectional")
			(die_length 21.132)
			(solder_mask_margin 0.02)
		)
		(pad "AJ9" smd circle
			(at -6.5 13.5)
			(size 0.5 0.5)
			(property pad_prop_bga)
			(layers "F.Cu" "F.Mask" "F.Paste")
			(net 481 "unconnected-(U1E-IO_L15P_T2_DQS_33-PadAJ9)")
			(pinfunction "IO_L15P_T2_DQS_33")
			(pintype "bidirectional+no_connect")
			(die_length 18.988)
			(solder_mask_margin 0.02)
		)
		(pad "AJ10" smd circle
			(at -5.5 13.5)
			(size 0.5 0.5)
			(property pad_prop_bga)
			(layers "F.Cu" "F.Mask" "F.Paste")
			(net 1 "GND")
			(pinfunction "GND")
			(pintype "passive")
			(solder_mask_margin 0.02)
		)
		(pad "AJ11" smd circle
			(at -4.5 13.5)
			(size 0.5 0.5)
			(property pad_prop_bga)
			(layers "F.Cu" "F.Mask" "F.Paste")
			(net 482 "unconnected-(U1E-IO_L18N_T2_33-PadAJ11)")
			(pinfunction "IO_L18N_T2_33")
			(pintype "bidirectional+no_connect")
			(die_length 18.518)
			(solder_mask_margin 0.02)
		)
		(pad "AJ12" smd circle
			(at -3.5 13.5)
			(size 0.5 0.5)
			(property pad_prop_bga)
			(layers "F.Cu" "F.Mask" "F.Paste")
			(net 408 "/FPGA Bank 33 & 34/USR_FLASH_0.CLK")
			(pinfunction "IO_L22N_T3_33")
			(pintype "bidirectional")
			(die_length 21.055)
			(solder_mask_margin 0.02)
		)
		(pad "AJ13" smd circle
			(at -2.5 13.5)
			(size 0.5 0.5)
			(property pad_prop_bga)
			(layers "F.Cu" "F.Mask" "F.Paste")
			(net 410 "/FPGA Bank 33 & 34/USR_FLASH_0.DQ0")
			(pinfunction "IO_L22P_T3_33")
			(pintype "bidirectional")
			(die_length 20.602)
			(solder_mask_margin 0.02)
		)
		(pad "AJ14" smd circle
			(at -1.5 13.5)
			(size 0.5 0.5)
			(property pad_prop_bga)
			(layers "F.Cu" "F.Mask" "F.Paste")
			(net 484 "unconnected-(U1E-IO_L21N_T3_DQS_33-PadAJ14)")
			(pinfunction "IO_L21N_T3_DQS_33")
			(pintype "bidirectional+no_connect")
			(die_length 23.179)
			(solder_mask_margin 0.02)
		)
		(pad "AJ15" smd circle
			(at -0.5 13.5)
			(size 0.5 0.5)
			(property pad_prop_bga)
			(layers "F.Cu" "F.Mask" "F.Paste")
			(net 26 "+1V8")
			(pinfunction "VCCO_32")
			(pintype "passive")
			(solder_mask_margin 0.02)
		)
		(pad "AJ16" smd circle
			(at 0.5 13.5)
			(size 0.5 0.5)
			(property pad_prop_bga)
			(layers "F.Cu" "F.Mask" "F.Paste")
			(net 653 "unconnected-(U1D-IO_L3N_T0_DQS_32-PadAJ16)")
			(pinfunction "IO_L3N_T0_DQS_32")
			(pintype "bidirectional+no_connect")
			(die_length 21.232)
			(solder_mask_margin 0.02)
		)
		(pad "AJ17" smd circle
			(at 1.5 13.5)
			(size 0.5 0.5)
			(property pad_prop_bga)
			(layers "F.Cu" "F.Mask" "F.Paste")
			(net 693 "/FPGA Bank 12 & 13/USB_USER.VMO")
			(pinfunction "IO_L5N_T0_32")
			(pintype "bidirectional")
			(die_length 21.569)
			(solder_mask_margin 0.02)
		)
		(pad "AJ18" smd circle
			(at 2.5 13.5)
			(size 0.5 0.5)
			(property pad_prop_bga)
			(layers "F.Cu" "F.Mask" "F.Paste")
			(net 694 "unconnected-(U1D-IO_L9P_T1_DQS_32-PadAJ18)")
			(pinfunction "IO_L9P_T1_DQS_32")
			(pintype "bidirectional+no_connect")
			(die_length 21.796)
			(solder_mask_margin 0.02)
		)
		(pad "AJ19" smd circle
			(at 3.5 13.5)
			(size 0.5 0.5)
			(property pad_prop_bga)
			(layers "F.Cu" "F.Mask" "F.Paste")
			(net 774 "unconnected-(U1D-IO_L7P_T1_32-PadAJ19)")
			(pinfunction "IO_L7P_T1_32")
			(pintype "bidirectional+no_connect")
			(die_length 23.335)
			(solder_mask_margin 0.02)
		)
		(pad "AJ20" smd circle
			(at 4.5 13.5)
			(size 0.5 0.5)
			(property pad_prop_bga)
			(layers "F.Cu" "F.Mask" "F.Paste")
			(net 1 "GND")
			(pinfunction "GND")
			(pintype "passive")
			(solder_mask_margin 0.02)
		)
		(pad "AJ21" smd circle
			(at 5.5 13.5)
			(size 0.5 0.5)
			(property pad_prop_bga)
			(layers "F.Cu" "F.Mask" "F.Paste")
			(net 489 "/FPGA Bank 12 & 13/CW_HEADER.IO1")
			(pinfunction "IO_L23N_T3_12")
			(pintype "bidirectional")
			(die_length 11.355)
			(solder_mask_margin 0.02)
		)
		(pad "AJ22" smd circle
			(at 6.5 13.5)
			(size 0.5 0.5)
			(property pad_prop_bga)
			(layers "F.Cu" "F.Mask" "F.Paste")
			(net 1353 "/SUP_MCU.A1")
			(pinfunction "IO_L21P_T3_DQS_12")
			(pintype "bidirectional")
			(die_length 12.698)
			(solder_mask_margin 0.02)
		)
		(pad "AJ23" smd circle
			(at 7.5 13.5)
			(size 0.5 0.5)
			(property pad_prop_bga)
			(layers "F.Cu" "F.Mask" "F.Paste")
			(net 1360 "/SUP_MCU.A3")
			(pinfunction "IO_L21N_T3_DQS_12")
			(pintype "bidirectional")
			(die_length 12.727)
			(solder_mask_margin 0.02)
		)
		(pad "AJ24" smd circle
			(at 8.5 13.5)
			(size 0.5 0.5)
			(property pad_prop_bga)
			(layers "F.Cu" "F.Mask" "F.Paste")
			(net 1367 "/SUP_MCU.A19")
			(pinfunction "IO_L15P_T2_DQS_12")
			(pintype "bidirectional")
			(die_length 14.604)
			(solder_mask_margin 0.02)
		)
		(pad "AJ25" smd circle
			(at 9.5 13.5)
			(size 0.5 0.5)
			(property pad_prop_bga)
			(layers "F.Cu" "F.Mask" "F.Paste")
			(net 24 "+3V3")
			(pinfunction "VCCO_13")
			(pintype "passive")
			(solder_mask_margin 0.02)
		)
		(pad "AJ26" smd circle
			(at 10.5 13.5)
			(size 0.5 0.5)
			(property pad_prop_bga)
			(layers "F.Cu" "F.Mask" "F.Paste")
			(net 776 "unconnected-(U1A-IO_L24P_T3_13-PadAJ26)")
			(pinfunction "IO_L24P_T3_13")
			(pintype "bidirectional+no_connect")
			(die_length 18.345)
			(solder_mask_margin 0.02)
		)
	)
)
